(kicad_pcb
	(version 20260206)
	(generator "pcbnew")
	(generator_version "10.0")
	(general
		(thickness 1.6)
		(legacy_teardrops no)
	)
	(paper "A4")
	(title_block
		(title "Bryce Canyon_SCC_16316-1_OCP.brd")
		(comment 1 "Bryce Canyon / footprint 146 of 1561 (CN2), pads 1-72 of 342")
	)
	(layers
		(0 "F.Cu" signal "TOP")
		(4 "In1.Cu" signal "L2GND")
		(6 "In2.Cu" signal "L3")
		(8 "In3.Cu" signal "L4VCC")
		(10 "In4.Cu" signal "L5VCC")
		(12 "In5.Cu" signal "L6")
		(14 "In6.Cu" signal "L7GND")
		(2 "B.Cu" signal "BOTTOM")
		(9 "F.Adhes" user "F.Adhesive")
		(11 "B.Adhes" user "B.Adhesive")
		(13 "F.Paste" user "Package Geometry/Pastemask Top")
		(15 "B.Paste" user "Package Geometry/Pastemask Bottom")
		(5 "F.SilkS" user "Ref Des/Silkscreen Top")
		(7 "B.SilkS" user "Ref Des/Silkscreen Bottom")
		(1 "F.Mask" user "Board Geometry/Soldermask Top")
		(3 "B.Mask" user "Board Geometry/Soldermask Bottom")
		(17 "Dwgs.User" user "User.Drawings")
		(19 "Cmts.User" user "User.Comments")
		(21 "Eco1.User" user "User.Eco1")
		(23 "Eco2.User" user "User.Eco2")
		(25 "Edge.Cuts" user "Board Geometry/Outline")
		(27 "Margin" user)
		(31 "F.CrtYd" user "Package Geometry/Place Bound Top")
		(29 "B.CrtYd" user "Package Geometry/Place Bound Bottom")
		(35 "F.Fab" user "Ref Des/Assembly Top")
		(33 "B.Fab" user "Ref Des/Assembly Bottom")
	)
	(footprint ""
		(layer "F.Cu")
		(at 86.000082 -3.800094)
		(property "Reference" "CN2"
			(at 0 0 0)
			(layer "F.SilkS")
			(hide yes)
			(effects
				(font
					(size 1.27 1.27)
				)
			)
		)
		(property "Value" "AMP-CONN342-10R-3-GP"
			(at -12.8905 -12.5222 0)
			(unlocked yes)
			(layer "F.Fab")
			(hide yes)
			(effects
				(font
					(size 1.016 1.016)
					(thickness 0.1524)
				)
			)
		)
		(property "Device Type" "PREFIT-342P-648260H400"
			(at -12.8905 -14.0462 0)
			(unlocked yes)
			(layer "F.Fab")
			(hide yes)
			(effects
				(font
					(size 1.016 1.016)
					(thickness 0.1524)
				)
			)
		)
		(duplicate_pad_numbers_are_jumpers no)
		(pad "A1" thru_hole circle
			(at 0 0)
			(size 0.762 0.762)
			(drill 0.359918)
			(layers "*.Cu" "*.Mask")
			(remove_unused_layers no)
			(net "PHY_DPB_TO_SCC_12_DN")
			(clearance 0.1651)
			(thermal_gap 0.1651)
		)
		(pad "A2" thru_hole circle
			(at 1.800098 1.199896)
			(size 0.762 0.762)
			(drill 0.359918)
			(layers "*.Cu" "*.Mask")
			(remove_unused_layers no)
			(net "PHY_DPB_TO_SCC_13_DN")
			(clearance 0.1651)
			(thermal_gap 0.1651)
		)
		(pad "A3" thru_hole circle
			(at 3.599942 0)
			(size 0.762 0.762)
			(drill 0.359918)
			(layers "*.Cu" "*.Mask")
			(remove_unused_layers no)
			(net "PHY_DPB_TO_SCC_14_DN")
			(clearance 0.1651)
			(thermal_gap 0.1651)
		)
		(pad "A4" thru_hole circle
			(at 5.40004 1.199896)
			(size 0.762 0.762)
			(drill 0.359918)
			(layers "*.Cu" "*.Mask")
			(remove_unused_layers no)
			(net "PHY_DPB_TO_SCC_15_DN")
			(clearance 0.1651)
			(thermal_gap 0.1651)
		)
		(pad "A5" thru_hole circle
			(at 7.199884 0)
			(size 0.762 0.762)
			(drill 0.359918)
			(layers "*.Cu" "*.Mask")
			(remove_unused_layers no)
			(net "PHY_DPB_TO_SCC_16_DN")
			(clearance 0.1651)
			(thermal_gap 0.1651)
		)
		(pad "A6" thru_hole circle
			(at 8.999982 1.199896)
			(size 0.762 0.762)
			(drill 0.359918)
			(layers "*.Cu" "*.Mask")
			(remove_unused_layers no)
			(net "PHY_DPB_TO_SCC_17_DN")
			(clearance 0.1651)
			(thermal_gap 0.1651)
		)
		(pad "A7" thru_hole circle
			(at 10.80008 0)
			(size 0.762 0.762)
			(drill 0.359918)
			(layers "*.Cu" "*.Mask")
			(remove_unused_layers no)
			(net "PHY_DPB_TO_SCC_18_DN")
			(clearance 0.1651)
			(thermal_gap 0.1651)
		)
		(pad "A8" thru_hole circle
			(at 12.599924 1.199896)
			(size 0.762 0.762)
			(drill 0.359918)
			(layers "*.Cu" "*.Mask")
			(remove_unused_layers no)
			(net "PHY_DPB_TO_SCC_19_DN")
			(clearance 0.1651)
			(thermal_gap 0.1651)
		)
		(pad "A9" thru_hole circle
			(at 14.400022 0)
			(size 0.762 0.762)
			(drill 0.359918)
			(layers "*.Cu" "*.Mask")
			(remove_unused_layers no)
			(net "PHY_DPB_TO_SCC_20_DN")
			(clearance 0.1651)
			(thermal_gap 0.1651)
		)
		(pad "A10" thru_hole circle
			(at 16.20012 1.199896)
			(size 0.762 0.762)
			(drill 0.359918)
			(layers "*.Cu" "*.Mask")
			(remove_unused_layers no)
			(net "PHY_DPB_TO_SCC_21_DN")
			(clearance 0.1651)
			(thermal_gap 0.1651)
		)
		(pad "A11" thru_hole circle
			(at 17.999964 0)
			(size 0.762 0.762)
			(drill 0.359918)
			(layers "*.Cu" "*.Mask")
			(remove_unused_layers no)
			(net "PHY_DPB_TO_SCC_22_DN")
			(clearance 0.1651)
			(thermal_gap 0.1651)
		)
		(pad "A12" thru_hole circle
			(at 19.800062 1.199896)
			(size 0.762 0.762)
			(drill 0.359918)
			(layers "*.Cu" "*.Mask")
			(remove_unused_layers no)
			(net "PHY_DPB_TO_SCC_23_DN")
			(clearance 0.1651)
			(thermal_gap 0.1651)
		)
		(pad "A13" thru_hole circle
			(at 21.599906 0)
			(size 0.762 0.762)
			(drill 0.359918)
			(layers "*.Cu" "*.Mask")
			(remove_unused_layers no)
			(net "PHY_DPB_TO_SCC_24_DN")
			(clearance 0.1651)
			(thermal_gap 0.1651)
		)
		(pad "A14" thru_hole circle
			(at 23.400004 1.199896)
			(size 0.762 0.762)
			(drill 0.359918)
			(layers "*.Cu" "*.Mask")
			(remove_unused_layers no)
			(net "PHY_DPB_TO_SCC_25_DN")
			(clearance 0.1651)
			(thermal_gap 0.1651)
		)
		(pad "A15" thru_hole circle
			(at 25.200102 0)
			(size 0.762 0.762)
			(drill 0.359918)
			(layers "*.Cu" "*.Mask")
			(remove_unused_layers no)
			(net "PHY_DPB_TO_SCC_26_DN")
			(clearance 0.1651)
			(thermal_gap 0.1651)
		)
		(pad "A16" thru_hole circle
			(at 26.999946 1.199896)
			(size 0.762 0.762)
			(drill 0.359918)
			(layers "*.Cu" "*.Mask")
			(remove_unused_layers no)
			(net "PHY_DPB_TO_SCC_27_DN")
			(clearance 0.1651)
			(thermal_gap 0.1651)
		)
		(pad "A17" thru_hole circle
			(at 28.800044 0)
			(size 0.762 0.762)
			(drill 0.359918)
			(layers "*.Cu" "*.Mask")
			(remove_unused_layers no)
			(net "PHY_DPB_TO_SCC_32_DN")
			(clearance 0.1651)
			(thermal_gap 0.1651)
		)
		(pad "A18" thru_hole circle
			(at 30.599888 1.199896)
			(size 0.762 0.762)
			(drill 0.359918)
			(layers "*.Cu" "*.Mask")
			(remove_unused_layers no)
			(net "PHY_DPB_TO_SCC_33_DN")
			(clearance 0.1651)
			(thermal_gap 0.1651)
		)
		(pad "A19" thru_hole circle
			(at 32.399986 0)
			(size 0.762 0.762)
			(drill 0.359918)
			(layers "*.Cu" "*.Mask")
			(remove_unused_layers no)
			(net "PHY_DPB_TO_SCC_34_DN")
			(clearance 0.1651)
			(thermal_gap 0.1651)
		)
		(pad "A20" thru_hole circle
			(at 34.200084 1.199896)
			(size 0.762 0.762)
			(drill 0.359918)
			(layers "*.Cu" "*.Mask")
			(remove_unused_layers no)
			(net "PHY_DPB_TO_SCC_35_DN")
			(clearance 0.1651)
			(thermal_gap 0.1651)
		)
		(pad "A21" thru_hole circle
			(at 35.999928 0)
			(size 0.762 0.762)
			(drill 0.359918)
			(layers "*.Cu" "*.Mask")
			(remove_unused_layers no)
			(net "PHY_DPB_TO_SCC_36_DN")
			(clearance 0.1651)
			(thermal_gap 0.1651)
		)
		(pad "A22" thru_hole circle
			(at 37.800026 1.199896)
			(size 0.762 0.762)
			(drill 0.359918)
			(layers "*.Cu" "*.Mask")
			(remove_unused_layers no)
			(net "PHY_DPB_TO_SCC_37_DN")
			(clearance 0.1651)
			(thermal_gap 0.1651)
		)
		(pad "A23" thru_hole circle
			(at 39.600124 0)
			(size 0.762 0.762)
			(drill 0.359918)
			(layers "*.Cu" "*.Mask")
			(remove_unused_layers no)
			(net "PHY_DPB_TO_SCC_38_DN")
			(clearance 0.1651)
			(thermal_gap 0.1651)
		)
		(pad "A24" thru_hole circle
			(at 41.399968 1.199896)
			(size 0.762 0.762)
			(drill 0.359918)
			(layers "*.Cu" "*.Mask")
			(remove_unused_layers no)
			(net "PHY_DPB_TO_SCC_39_DN")
			(clearance 0.1651)
			(thermal_gap 0.1651)
		)
		(pad "A25" thru_hole circle
			(at 43.200066 0)
			(size 0.762 0.762)
			(drill 0.359918)
			(layers "*.Cu" "*.Mask")
			(remove_unused_layers no)
			(net "PHY_DPB_TO_SCC_28_DN")
			(clearance 0.1651)
			(thermal_gap 0.1651)
		)
		(pad "A26" thru_hole circle
			(at 44.99991 1.199896)
			(size 0.762 0.762)
			(drill 0.359918)
			(layers "*.Cu" "*.Mask")
			(remove_unused_layers no)
			(net "PHY_DPB_TO_SCC_29_DN")
			(clearance 0.1651)
			(thermal_gap 0.1651)
		)
		(pad "A27" thru_hole circle
			(at 46.800008 0)
			(size 0.762 0.762)
			(drill 0.359918)
			(layers "*.Cu" "*.Mask")
			(remove_unused_layers no)
			(net "PHY_DPB_TO_SCC_30_DN")
			(clearance 0.1651)
			(thermal_gap 0.1651)
		)
		(pad "A28" thru_hole circle
			(at 48.600106 1.199896)
			(size 0.762 0.762)
			(drill 0.359918)
			(layers "*.Cu" "*.Mask")
			(remove_unused_layers no)
			(net "PHY_DPB_TO_SCC_31_DN")
			(clearance 0.1651)
			(thermal_gap 0.1651)
		)
		(pad "A29" thru_hole circle
			(at 50.39995 0)
			(size 0.762 0.762)
			(drill 0.359918)
			(layers "*.Cu" "*.Mask")
			(remove_unused_layers no)
			(net "PHY_DPB_TO_SCC_0_DN")
			(clearance 0.1651)
			(thermal_gap 0.1651)
		)
		(pad "A30" thru_hole circle
			(at 52.200048 1.199896)
			(size 0.762 0.762)
			(drill 0.359918)
			(layers "*.Cu" "*.Mask")
			(remove_unused_layers no)
			(net "PHY_DPB_TO_SCC_1_DN")
			(clearance 0.1651)
			(thermal_gap 0.1651)
		)
		(pad "A31" thru_hole circle
			(at 53.999892 0)
			(size 0.762 0.762)
			(drill 0.359918)
			(layers "*.Cu" "*.Mask")
			(remove_unused_layers no)
			(net "PHY_DPB_TO_SCC_2_DN")
			(clearance 0.1651)
			(thermal_gap 0.1651)
		)
		(pad "A32" thru_hole circle
			(at 55.79999 1.199896)
			(size 0.762 0.762)
			(drill 0.359918)
			(layers "*.Cu" "*.Mask")
			(remove_unused_layers no)
			(net "PHY_DPB_TO_SCC_3_DN")
			(clearance 0.1651)
			(thermal_gap 0.1651)
		)
		(pad "A33" thru_hole circle
			(at 57.600088 0)
			(size 0.762 0.762)
			(drill 0.359918)
			(layers "*.Cu" "*.Mask")
			(remove_unused_layers no)
			(net "PHY_DPB_TO_SCC_4_DN")
			(clearance 0.1651)
			(thermal_gap 0.1651)
		)
		(pad "A34" thru_hole circle
			(at 59.399932 1.199896)
			(size 0.762 0.762)
			(drill 0.359918)
			(layers "*.Cu" "*.Mask")
			(remove_unused_layers no)
			(net "PHY_DPB_TO_SCC_5_DN")
			(clearance 0.1651)
			(thermal_gap 0.1651)
		)
		(pad "A35" thru_hole circle
			(at 61.20003 0)
			(size 0.762 0.762)
			(drill 0.359918)
			(layers "*.Cu" "*.Mask")
			(remove_unused_layers no)
			(net "PHY_DPB_TO_SCC_6_DN")
			(clearance 0.1651)
			(thermal_gap 0.1651)
		)
		(pad "A36" thru_hole circle
			(at 62.999874 1.199896)
			(size 0.762 0.762)
			(drill 0.359918)
			(layers "*.Cu" "*.Mask")
			(remove_unused_layers no)
			(net "PHY_DPB_TO_SCC_7_DN")
			(clearance 0.1651)
			(thermal_gap 0.1651)
		)
		(pad "B1" thru_hole circle
			(at 0 -1.400048)
			(size 0.762 0.762)
			(drill 0.359918)
			(layers "*.Cu" "*.Mask")
			(remove_unused_layers no)
			(net "PHY_DPB_TO_SCC_12_DP")
			(clearance 0.1651)
			(thermal_gap 0.1651)
		)
		(pad "B2" thru_hole circle
			(at 1.800098 -0.199898)
			(size 0.762 0.762)
			(drill 0.359918)
			(layers "*.Cu" "*.Mask")
			(remove_unused_layers no)
			(net "PHY_DPB_TO_SCC_13_DP")
			(clearance 0.1651)
			(thermal_gap 0.1651)
		)
		(pad "B3" thru_hole circle
			(at 3.599942 -1.400048)
			(size 0.762 0.762)
			(drill 0.359918)
			(layers "*.Cu" "*.Mask")
			(remove_unused_layers no)
			(net "PHY_DPB_TO_SCC_14_DP")
			(clearance 0.1651)
			(thermal_gap 0.1651)
		)
		(pad "B4" thru_hole circle
			(at 5.40004 -0.199898)
			(size 0.762 0.762)
			(drill 0.359918)
			(layers "*.Cu" "*.Mask")
			(remove_unused_layers no)
			(net "PHY_DPB_TO_SCC_15_DP")
			(clearance 0.1651)
			(thermal_gap 0.1651)
		)
		(pad "B5" thru_hole circle
			(at 7.199884 -1.400048)
			(size 0.762 0.762)
			(drill 0.359918)
			(layers "*.Cu" "*.Mask")
			(remove_unused_layers no)
			(net "PHY_DPB_TO_SCC_16_DP")
			(clearance 0.1651)
			(thermal_gap 0.1651)
		)
		(pad "B6" thru_hole circle
			(at 8.999982 -0.199898)
			(size 0.762 0.762)
			(drill 0.359918)
			(layers "*.Cu" "*.Mask")
			(remove_unused_layers no)
			(net "PHY_DPB_TO_SCC_17_DP")
			(clearance 0.1651)
			(thermal_gap 0.1651)
		)
		(pad "B7" thru_hole circle
			(at 10.80008 -1.400048)
			(size 0.762 0.762)
			(drill 0.359918)
			(layers "*.Cu" "*.Mask")
			(remove_unused_layers no)
			(net "PHY_DPB_TO_SCC_18_DP")
			(clearance 0.1651)
			(thermal_gap 0.1651)
		)
		(pad "B8" thru_hole circle
			(at 12.599924 -0.199898)
			(size 0.762 0.762)
			(drill 0.359918)
			(layers "*.Cu" "*.Mask")
			(remove_unused_layers no)
			(net "PHY_DPB_TO_SCC_19_DP")
			(clearance 0.1651)
			(thermal_gap 0.1651)
		)
		(pad "B9" thru_hole circle
			(at 14.400022 -1.400048)
			(size 0.762 0.762)
			(drill 0.359918)
			(layers "*.Cu" "*.Mask")
			(remove_unused_layers no)
			(net "PHY_DPB_TO_SCC_20_DP")
			(clearance 0.1651)
			(thermal_gap 0.1651)
		)
		(pad "B10" thru_hole circle
			(at 16.20012 -0.199898)
			(size 0.762 0.762)
			(drill 0.359918)
			(layers "*.Cu" "*.Mask")
			(remove_unused_layers no)
			(net "PHY_DPB_TO_SCC_21_DP")
			(clearance 0.1651)
			(thermal_gap 0.1651)
		)
		(pad "B11" thru_hole circle
			(at 17.999964 -1.400048)
			(size 0.762 0.762)
			(drill 0.359918)
			(layers "*.Cu" "*.Mask")
			(remove_unused_layers no)
			(net "PHY_DPB_TO_SCC_22_DP")
			(clearance 0.1651)
			(thermal_gap 0.1651)
		)
		(pad "B12" thru_hole circle
			(at 19.800062 -0.199898)
			(size 0.762 0.762)
			(drill 0.359918)
			(layers "*.Cu" "*.Mask")
			(remove_unused_layers no)
			(net "PHY_DPB_TO_SCC_23_DP")
			(clearance 0.1651)
			(thermal_gap 0.1651)
		)
		(pad "B13" thru_hole circle
			(at 21.599906 -1.400048)
			(size 0.762 0.762)
			(drill 0.359918)
			(layers "*.Cu" "*.Mask")
			(remove_unused_layers no)
			(net "PHY_DPB_TO_SCC_24_DP")
			(clearance 0.1651)
			(thermal_gap 0.1651)
		)
		(pad "B14" thru_hole circle
			(at 23.400004 -0.199898)
			(size 0.762 0.762)
			(drill 0.359918)
			(layers "*.Cu" "*.Mask")
			(remove_unused_layers no)
			(net "PHY_DPB_TO_SCC_25_DP")
			(clearance 0.1651)
			(thermal_gap 0.1651)
		)
		(pad "B15" thru_hole circle
			(at 25.200102 -1.400048)
			(size 0.762 0.762)
			(drill 0.359918)
			(layers "*.Cu" "*.Mask")
			(remove_unused_layers no)
			(net "PHY_DPB_TO_SCC_26_DP")
			(clearance 0.1651)
			(thermal_gap 0.1651)
		)
		(pad "B16" thru_hole circle
			(at 26.999946 -0.199898)
			(size 0.762 0.762)
			(drill 0.359918)
			(layers "*.Cu" "*.Mask")
			(remove_unused_layers no)
			(net "PHY_DPB_TO_SCC_27_DP")
			(clearance 0.1651)
			(thermal_gap 0.1651)
		)
		(pad "B17" thru_hole circle
			(at 28.800044 -1.400048)
			(size 0.762 0.762)
			(drill 0.359918)
			(layers "*.Cu" "*.Mask")
			(remove_unused_layers no)
			(net "PHY_DPB_TO_SCC_32_DP")
			(clearance 0.1651)
			(thermal_gap 0.1651)
		)
		(pad "B18" thru_hole circle
			(at 30.599888 -0.199898)
			(size 0.762 0.762)
			(drill 0.359918)
			(layers "*.Cu" "*.Mask")
			(remove_unused_layers no)
			(net "PHY_DPB_TO_SCC_33_DP")
			(clearance 0.1651)
			(thermal_gap 0.1651)
		)
		(pad "B19" thru_hole circle
			(at 32.399986 -1.400048)
			(size 0.762 0.762)
			(drill 0.359918)
			(layers "*.Cu" "*.Mask")
			(remove_unused_layers no)
			(net "PHY_DPB_TO_SCC_34_DP")
			(clearance 0.1651)
			(thermal_gap 0.1651)
		)
		(pad "B20" thru_hole circle
			(at 34.200084 -0.199898)
			(size 0.762 0.762)
			(drill 0.359918)
			(layers "*.Cu" "*.Mask")
			(remove_unused_layers no)
			(net "PHY_DPB_TO_SCC_35_DP")
			(clearance 0.1651)
			(thermal_gap 0.1651)
		)
		(pad "B21" thru_hole circle
			(at 35.999928 -1.400048)
			(size 0.762 0.762)
			(drill 0.359918)
			(layers "*.Cu" "*.Mask")
			(remove_unused_layers no)
			(net "PHY_DPB_TO_SCC_36_DP")
			(clearance 0.1651)
			(thermal_gap 0.1651)
		)
		(pad "B22" thru_hole circle
			(at 37.800026 -0.199898)
			(size 0.762 0.762)
			(drill 0.359918)
			(layers "*.Cu" "*.Mask")
			(remove_unused_layers no)
			(net "PHY_DPB_TO_SCC_37_DP")
			(clearance 0.1651)
			(thermal_gap 0.1651)
		)
		(pad "B23" thru_hole circle
			(at 39.600124 -1.400048)
			(size 0.762 0.762)
			(drill 0.359918)
			(layers "*.Cu" "*.Mask")
			(remove_unused_layers no)
			(net "PHY_DPB_TO_SCC_38_DP")
			(clearance 0.1651)
			(thermal_gap 0.1651)
		)
		(pad "B24" thru_hole circle
			(at 41.399968 -0.199898)
			(size 0.762 0.762)
			(drill 0.359918)
			(layers "*.Cu" "*.Mask")
			(remove_unused_layers no)
			(net "PHY_DPB_TO_SCC_39_DP")
			(clearance 0.1651)
			(thermal_gap 0.1651)
		)
		(pad "B25" thru_hole circle
			(at 43.200066 -1.400048)
			(size 0.762 0.762)
			(drill 0.359918)
			(layers "*.Cu" "*.Mask")
			(remove_unused_layers no)
			(net "PHY_DPB_TO_SCC_28_DP")
			(clearance 0.1651)
			(thermal_gap 0.1651)
		)
		(pad "B26" thru_hole circle
			(at 44.99991 -0.199898)
			(size 0.762 0.762)
			(drill 0.359918)
			(layers "*.Cu" "*.Mask")
			(remove_unused_layers no)
			(net "PHY_DPB_TO_SCC_29_DP")
			(clearance 0.1651)
			(thermal_gap 0.1651)
		)
		(pad "B27" thru_hole circle
			(at 46.800008 -1.400048)
			(size 0.762 0.762)
			(drill 0.359918)
			(layers "*.Cu" "*.Mask")
			(remove_unused_layers no)
			(net "PHY_DPB_TO_SCC_30_DP")
			(clearance 0.1651)
			(thermal_gap 0.1651)
		)
		(pad "B28" thru_hole circle
			(at 48.600106 -0.199898)
			(size 0.762 0.762)
			(drill 0.359918)
			(layers "*.Cu" "*.Mask")
			(remove_unused_layers no)
			(net "PHY_DPB_TO_SCC_31_DP")
			(clearance 0.1651)
			(thermal_gap 0.1651)
		)
		(pad "B29" thru_hole circle
			(at 50.39995 -1.400048)
			(size 0.762 0.762)
			(drill 0.359918)
			(layers "*.Cu" "*.Mask")
			(remove_unused_layers no)
			(net "PHY_DPB_TO_SCC_0_DP")
			(clearance 0.1651)
			(thermal_gap 0.1651)
		)
		(pad "B30" thru_hole circle
			(at 52.200048 -0.199898)
			(size 0.762 0.762)
			(drill 0.359918)
			(layers "*.Cu" "*.Mask")
			(remove_unused_layers no)
			(net "PHY_DPB_TO_SCC_1_DP")
			(clearance 0.1651)
			(thermal_gap 0.1651)
		)
		(pad "B31" thru_hole circle
			(at 53.999892 -1.400048)
			(size 0.762 0.762)
			(drill 0.359918)
			(layers "*.Cu" "*.Mask")
			(remove_unused_layers no)
			(net "PHY_DPB_TO_SCC_2_DP")
			(clearance 0.1651)
			(thermal_gap 0.1651)
		)
		(pad "B32" thru_hole circle
			(at 55.79999 -0.199898)
			(size 0.762 0.762)
			(drill 0.359918)
			(layers "*.Cu" "*.Mask")
			(remove_unused_layers no)
			(net "PHY_DPB_TO_SCC_3_DP")
			(clearance 0.1651)
			(thermal_gap 0.1651)
		)
		(pad "B33" thru_hole circle
			(at 57.600088 -1.400048)
			(size 0.762 0.762)
			(drill 0.359918)
			(layers "*.Cu" "*.Mask")
			(remove_unused_layers no)
			(net "PHY_DPB_TO_SCC_4_DP")
			(clearance 0.1651)
			(thermal_gap 0.1651)
		)
		(pad "B34" thru_hole circle
			(at 59.399932 -0.199898)
			(size 0.762 0.762)
			(drill 0.359918)
			(layers "*.Cu" "*.Mask")
			(remove_unused_layers no)
			(net "PHY_DPB_TO_SCC_5_DP")
			(clearance 0.1651)
			(thermal_gap 0.1651)
		)
		(pad "B35" thru_hole circle
			(at 61.20003 -1.400048)
			(size 0.762 0.762)
			(drill 0.359918)
			(layers "*.Cu" "*.Mask")
			(remove_unused_layers no)
			(net "PHY_DPB_TO_SCC_6_DP")
			(clearance 0.1651)
			(thermal_gap 0.1651)
		)
		(pad "B36" thru_hole circle
			(at 62.999874 -0.199898)
			(size 0.762 0.762)
			(drill 0.359918)
			(layers "*.Cu" "*.Mask")
			(remove_unused_layers no)
			(net "PHY_DPB_TO_SCC_7_DP")
			(clearance 0.1651)
			(thermal_gap 0.1651)
		)
	)
)
